# T6G (Grand Teton) — schematic netlist excerpt (pin names and nets, part order shuffled) for the footprints in the layout excerpt that follows; sources: Cadence DE-HDL packaged netlist, KiCad conversion of 04192023_DAF0TMB3IC0_F0TG_MB_C_brd_V02_OCP.brd

R6061  Q_RES  4.7K 5% EMPTY  pkg 0402LF  page 83 : A = P12V_OCP_V3_2_EN_R ; B = P3V3_AUX

PU293  MP5016GQHLZ  MP5016GQH-L-Z IC  pkg QFN8_2X1-5  page 147
  VCC  = P3V3_AUX
  GND  = GND
  ILIMIT  = P3V3_E1S_ILIMIT_0
  MODE  = P3V3_E1S_MODE_0
  SOURCE  = P3V3_E1S_0_R
  GATE  = P3V3_E1S_GATE_0_PU293
  EN  = P3V3_E1S_EN_0_R2
  DV_DT  = P3V3_E1S_DVDT_0

(kicad_pcb
	(version 20260206)
	(generator "pcbnew")
	(generator_version "10.0")
	(general
		(thickness 1.6)
		(legacy_teardrops no)
	)
	(paper "A4")
	(title_block
		(title "04192023_DAF0TMB3IC0_F0TG_MB_C_brd_V02_OCP.brd")
		(comment 1 "Grand Teton / footprints 3299-3300 of 8354")
	)
	(layers
		(0 "F.Cu" signal "TOP")
		(4 "In1.Cu" signal "GND")
		(6 "In2.Cu" signal "IN1")
		(8 "In3.Cu" signal "GND1")
		(10 "In4.Cu" signal "IN2")
		(12 "In5.Cu" signal "GND2")
		(14 "In6.Cu" signal "IN3")
		(16 "In7.Cu" signal "GND3")
		(18 "In8.Cu" signal "VCC")
		(20 "In9.Cu" signal "VCC1")
		(22 "In10.Cu" signal "GND4")
		(24 "In11.Cu" signal "IN4")
		(26 "In12.Cu" signal "GND5")
		(28 "In13.Cu" signal "IN5")
		(30 "In14.Cu" signal "GND6")
		(32 "In15.Cu" signal "IN6")
		(34 "In16.Cu" signal "GND7")
		(2 "B.Cu" signal "BOTTOM")
		(9 "F.Adhes" user "F.Adhesive")
		(11 "B.Adhes" user "B.Adhesive")
		(13 "F.Paste" user "Package Geometry/Pastemask Top")
		(15 "B.Paste" user "Package Geometry/Pastemask Bottom")
		(5 "F.SilkS" user "Ref Des/Silkscreen Top")
		(7 "B.SilkS" user "Ref Des/Silkscreen Bottom")
		(1 "F.Mask" user "Board Geometry/Soldermask Top")
		(3 "B.Mask" user "Board Geometry/Soldermask Bottom")
		(17 "Dwgs.User" user "User.Drawings")
		(19 "Cmts.User" user "User.Comments")
		(21 "Eco1.User" user "User.Eco1")
		(23 "Eco2.User" user "User.Eco2")
		(25 "Edge.Cuts" user "Board Geometry/Outline")
		(27 "Margin" user)
		(31 "F.CrtYd" user "Package Geometry/Place Bound Top")
		(29 "B.CrtYd" user "Package Geometry/Place Bound Bottom")
		(35 "F.Fab" user "Ref Des/Assembly Top")
		(33 "B.Fab" user "Ref Des/Assembly Bottom")
	)
	(footprint ""
		(layer "F.Cu")
		(at 196.536564 -69.423788 -90)
		(property "Reference" "PU293"
			(at -3.945128 3.01625 0)
			(unlocked yes)
			(layer "F.SilkS")
			(effects
				(font
					(size 0.7874 0.5842)
					(thickness 0.1524)
				)
			)
		)
		(property "Value" ""
			(at 0 0 270)
			(layer "F.Fab")
			(effects
				(font
					(size 1.27 1.27)
				)
			)
		)
		(duplicate_pad_numbers_are_jumpers no)
		(fp_line
			(start -1.239774 1.495298)
			(end -1.239774 -1.495298)
			(stroke
				(width 0.1524)
				(type default)
			)
			(layer "F.SilkS")
		)
		(fp_line
			(start 1.239774 1.495298)
			(end -1.239774 1.495298)
			(stroke
				(width 0.1524)
				(type default)
			)
			(layer "F.SilkS")
		)
		(fp_line
			(start -1.239774 -1.495298)
			(end 1.239774 -1.495298)
			(stroke
				(width 0.1524)
				(type default)
			)
			(layer "F.SilkS")
		)
		(fp_line
			(start 1.239774 -1.495298)
			(end 1.239774 1.495298)
			(stroke
				(width 0.1524)
				(type default)
			)
			(layer "F.SilkS")
		)
		(fp_poly
			(pts
				(xy -2.047748 -0.638302) (xy -3.163824 -0.849122) (xy -2.54889 -1.657858)
			)
			(stroke
				(width 0)
				(type default)
			)
			(fill yes)
			(layer "F.SilkS")
		)
		(fp_line
			(start -0.8001 1.050036)
			(end -0.8001 -1.050036)
			(stroke
				(width 0.1)
				(type default)
			)
			(layer "F.Fab")
		)
		(fp_line
			(start 0.8001 1.050036)
			(end -0.8001 1.050036)
			(stroke
				(width 0.1)
				(type default)
			)
			(layer "F.Fab")
		)
		(fp_line
			(start -0.8001 -1.050036)
			(end 0.8001 -1.050036)
			(stroke
				(width 0.1)
				(type default)
			)
			(layer "F.Fab")
		)
		(fp_line
			(start 0.8001 -1.050036)
			(end 0.8001 1.050036)
			(stroke
				(width 0.1)
				(type default)
			)
			(layer "F.Fab")
		)
		(fp_poly
			(pts
				(xy -2.458974 -0.508) (xy -2.458974 0.508) (xy -1.442974 0)
			)
			(stroke
				(width 0)
				(type default)
			)
			(fill yes)
			(layer "F.Fab")
		)
		(pad "1_2" smd circle
			(at -0.374904 0)
			(size 0 0)
			(layers "F.Cu" "F.Mask" "F.Paste")
			(net "P3V3_AUX")
		)
		(pad "3" smd rect
			(at -0.499872 0.999998 270)
			(size 0.254 0.7112)
			(layers "F.Cu" "F.Mask" "F.Paste")
			(net "GND")
		)
		(pad "4" smd rect
			(at 0 0.999998 270)
			(size 0.254 0.7112)
			(layers "F.Cu" "F.Mask" "F.Paste")
			(net "P3V3_E1S_ILIMIT_0")
		)
		(pad "5" smd rect
			(at 0.499872 0.999998 270)
			(size 0.254 0.7112)
			(layers "F.Cu" "F.Mask" "F.Paste")
			(net "P3V3_E1S_MODE_0")
		)
		(pad "6_7" smd circle
			(at 0.374904 0 180)
			(size 0 0)
			(layers "F.Cu" "F.Mask" "F.Paste")
			(net "P3V3_E1S_0_R")
		)
		(pad "8" smd rect
			(at 0.499872 -0.999998 270)
			(size 0.254 0.7112)
			(layers "F.Cu" "F.Mask" "F.Paste")
			(net "P3V3_E1S_GATE_0_PU293")
		)
		(pad "9" smd rect
			(at 0 -0.999998 270)
			(size 0.254 0.7112)
			(layers "F.Cu" "F.Mask" "F.Paste")
			(net "P3V3_E1S_EN_0_R2")
		)
		(pad "10" smd rect
			(at -0.499872 -0.999998 270)
			(size 0.254 0.7112)
			(layers "F.Cu" "F.Mask" "F.Paste")
			(net "P3V3_E1S_DVDT_0")
		)
	)
	(footprint ""
		(layer "F.Cu")
		(at 205.262226 -125.817376)
		(property "Reference" "R6061"
			(at 0 0 0)
			(layer "F.SilkS")
			(hide yes)
			(effects
				(font
					(size 1.27 1.27)
				)
			)
		)
		(property "Value" ""
			(at 0 0 0)
			(layer "F.Fab")
			(effects
				(font
					(size 1.27 1.27)
				)
			)
		)
		(duplicate_pad_numbers_are_jumpers no)
		(fp_line
			(start -0.7874 -0.4064)
			(end 0.7874 -0.4064)
			(stroke
				(width 0.1524)
				(type default)
			)
			(layer "F.SilkS")
		)
		(fp_line
			(start -0.7874 0.4064)
			(end -0.7874 -0.4064)
			(stroke
				(width 0.1524)
				(type default)
			)
			(layer "F.SilkS")
		)
		(fp_line
			(start 0.7874 -0.4064)
			(end 0.7874 0.4064)
			(stroke
				(width 0.1524)
				(type default)
			)
			(layer "F.SilkS")
		)
		(fp_line
			(start 0.7874 0.4064)
			(end -0.7874 0.4064)
			(stroke
				(width 0.1524)
				(type default)
			)
			(layer "F.SilkS")
		)
		(fp_line
			(start -0.67945 -0.305054)
			(end -0.12065 -0.305054)
			(stroke
				(width 0.1)
				(type default)
			)
			(layer "F.Fab")
		)
		(fp_line
			(start -0.67945 0.3048)
			(end -0.67945 -0.305054)
			(stroke
				(width 0.1)
				(type default)
			)
			(layer "F.Fab")
		)
		(fp_line
			(start -0.12065 -0.305054)
			(end -0.12065 -0.2794)
			(stroke
				(width 0.1)
				(type default)
			)
			(layer "F.Fab")
		)
		(fp_line
			(start -0.12065 -0.2794)
			(end 0.12065 -0.2794)
			(stroke
				(width 0.1)
				(type default)
			)
			(layer "F.Fab")
		)
		(fp_line
			(start -0.12065 0.2794)
			(end -0.12065 0.3048)
			(stroke
				(width 0.1)
				(type default)
			)
			(layer "F.Fab")
		)
		(fp_line
			(start -0.12065 0.3048)
			(end -0.67945 0.3048)
			(stroke
				(width 0.1)
				(type default)
			)
			(layer "F.Fab")
		)
		(fp_line
			(start 0.120396 0.2794)
			(end -0.12065 0.2794)
			(stroke
				(width 0.1)
				(type default)
			)
			(layer "F.Fab")
		)
		(fp_line
			(start 0.120396 0.3048)
			(end 0.120396 0.2794)
			(stroke
				(width 0.1)
				(type default)
			)
			(layer "F.Fab")
		)
		(fp_line
			(start 0.12065 -0.3048)
			(end 0.67945 -0.3048)
			(stroke
				(width 0.1)
				(type default)
			)
			(layer "F.Fab")
		)
		(fp_line
			(start 0.12065 -0.2794)
			(end 0.12065 -0.3048)
			(stroke
				(width 0.1)
				(type default)
			)
			(layer "F.Fab")
		)
		(fp_line
			(start 0.67945 -0.3048)
			(end 0.67945 0.3048)
			(stroke
				(width 0.1)
				(type default)
			)
			(layer "F.Fab")
		)
		(fp_line
			(start 0.67945 0.3048)
			(end 0.120396 0.3048)
			(stroke
				(width 0.1)
				(type default)
			)
			(layer "F.Fab")
		)
		(pad "1" smd circle
			(at -0.40005 0)
			(size 0 0)
			(layers "F.Cu" "F.Mask" "F.Paste")
			(net "P12V_OCP_V3_2_EN_R")
		)
		(pad "2" smd circle
			(at 0.40005 0)
			(size 0 0)
			(layers "F.Cu" "F.Mask" "F.Paste")
			(net "P3V3_AUX")
		)
	)
)
